(kicad_pcb
	(version 20260206)
	(generator "pcbnew")
	(generator_version "10.0")
	(general
		(thickness 1.6)
		(legacy_teardrops no)
	)
	(paper "A4")
	(title_block
		(title "04192023_DAF0TMB3IC0_F0TG_MB_C_brd_V02_OCP.brd")
		(comment 1 "Grand Teton / footprints 2638-2643 of 8354")
	)
	(layers
		(0 "F.Cu" signal "TOP")
		(4 "In1.Cu" signal "GND")
		(6 "In2.Cu" signal "IN1")
		(8 "In3.Cu" signal "GND1")
		(10 "In4.Cu" signal "IN2")
		(12 "In5.Cu" signal "GND2")
		(14 "In6.Cu" signal "IN3")
		(16 "In7.Cu" signal "GND3")
		(18 "In8.Cu" signal "VCC")
		(20 "In9.Cu" signal "VCC1")
		(22 "In10.Cu" signal "GND4")
		(24 "In11.Cu" signal "IN4")
		(26 "In12.Cu" signal "GND5")
		(28 "In13.Cu" signal "IN5")
		(30 "In14.Cu" signal "GND6")
		(32 "In15.Cu" signal "IN6")
		(34 "In16.Cu" signal "GND7")
		(2 "B.Cu" signal "BOTTOM")
		(9 "F.Adhes" user "F.Adhesive")
		(11 "B.Adhes" user "B.Adhesive")
		(13 "F.Paste" user "Package Geometry/Pastemask Top")
		(15 "B.Paste" user "Package Geometry/Pastemask Bottom")
		(5 "F.SilkS" user "Ref Des/Silkscreen Top")
		(7 "B.SilkS" user "Ref Des/Silkscreen Bottom")
		(1 "F.Mask" user "Board Geometry/Soldermask Top")
		(3 "B.Mask" user "Board Geometry/Soldermask Bottom")
		(17 "Dwgs.User" user "User.Drawings")
		(19 "Cmts.User" user "User.Comments")
		(21 "Eco1.User" user "User.Eco1")
		(23 "Eco2.User" user "User.Eco2")
		(25 "Edge.Cuts" user "Board Geometry/Outline")
		(27 "Margin" user)
		(31 "F.CrtYd" user "Package Geometry/Place Bound Top")
		(29 "B.CrtYd" user "Package Geometry/Place Bound Bottom")
		(35 "F.Fab" user "Ref Des/Assembly Top")
		(33 "B.Fab" user "Ref Des/Assembly Bottom")
	)
	(footprint ""
		(layer "F.Cu")
		(at 408.758644 -139.362942 -90)
		(property "Reference" "PR8092"
			(at 0 0 270)
			(layer "F.SilkS")
			(hide yes)
			(effects
				(font
					(size 1.27 1.27)
				)
			)
		)
		(property "Value" ""
			(at 0 0 270)
			(layer "F.Fab")
			(effects
				(font
					(size 1.27 1.27)
				)
			)
		)
		(duplicate_pad_numbers_are_jumpers no)
		(fp_line
			(start -0.7874 0.4064)
			(end -0.7874 -0.4064)
			(stroke
				(width 0.1524)
				(type default)
			)
			(layer "F.SilkS")
		)
		(fp_line
			(start 0.7874 0.4064)
			(end -0.7874 0.4064)
			(stroke
				(width 0.1524)
				(type default)
			)
			(layer "F.SilkS")
		)
		(fp_line
			(start -0.7874 -0.4064)
			(end 0.7874 -0.4064)
			(stroke
				(width 0.1524)
				(type default)
			)
			(layer "F.SilkS")
		)
		(fp_line
			(start 0.7874 -0.4064)
			(end 0.7874 0.4064)
			(stroke
				(width 0.1524)
				(type default)
			)
			(layer "F.SilkS")
		)
		(fp_line
			(start -0.67945 0.3048)
			(end -0.67945 -0.305054)
			(stroke
				(width 0.1)
				(type default)
			)
			(layer "F.Fab")
		)
		(fp_line
			(start -0.12065 0.3048)
			(end -0.67945 0.3048)
			(stroke
				(width 0.1)
				(type default)
			)
			(layer "F.Fab")
		)
		(fp_line
			(start 0.120396 0.3048)
			(end 0.120396 0.2794)
			(stroke
				(width 0.1)
				(type default)
			)
			(layer "F.Fab")
		)
		(fp_line
			(start 0.67945 0.3048)
			(end 0.120396 0.3048)
			(stroke
				(width 0.1)
				(type default)
			)
			(layer "F.Fab")
		)
		(fp_line
			(start -0.12065 0.2794)
			(end -0.12065 0.3048)
			(stroke
				(width 0.1)
				(type default)
			)
			(layer "F.Fab")
		)
		(fp_line
			(start 0.120396 0.2794)
			(end -0.12065 0.2794)
			(stroke
				(width 0.1)
				(type default)
			)
			(layer "F.Fab")
		)
		(fp_line
			(start -0.12065 -0.2794)
			(end 0.12065 -0.2794)
			(stroke
				(width 0.1)
				(type default)
			)
			(layer "F.Fab")
		)
		(fp_line
			(start 0.12065 -0.2794)
			(end 0.12065 -0.3048)
			(stroke
				(width 0.1)
				(type default)
			)
			(layer "F.Fab")
		)
		(fp_line
			(start 0.12065 -0.3048)
			(end 0.67945 -0.3048)
			(stroke
				(width 0.1)
				(type default)
			)
			(layer "F.Fab")
		)
		(fp_line
			(start 0.67945 -0.3048)
			(end 0.67945 0.3048)
			(stroke
				(width 0.1)
				(type default)
			)
			(layer "F.Fab")
		)
		(fp_line
			(start -0.67945 -0.305054)
			(end -0.12065 -0.305054)
			(stroke
				(width 0.1)
				(type default)
			)
			(layer "F.Fab")
		)
		(fp_line
			(start -0.12065 -0.305054)
			(end -0.12065 -0.2794)
			(stroke
				(width 0.1)
				(type default)
			)
			(layer "F.Fab")
		)
		(pad "1" smd circle
			(at -0.40005 0 270)
			(size 0 0)
			(layers "F.Cu" "F.Mask" "F.Paste")
			(net "P5V_AUX_FB")
		)
		(pad "2" smd circle
			(at 0.40005 0 270)
			(size 0 0)
			(layers "F.Cu" "F.Mask" "F.Paste")
			(net "P5V_AUX")
		)
	)
	(footprint ""
		(layer "F.Cu")
		(at 172.878242 -28.03779 90)
		(property "Reference" "PR4010"
			(at 0 0 90)
			(layer "F.SilkS")
			(hide yes)
			(effects
				(font
					(size 1.27 1.27)
				)
			)
		)
		(property "Value" ""
			(at 0 0 90)
			(layer "F.Fab")
			(effects
				(font
					(size 1.27 1.27)
				)
			)
		)
		(duplicate_pad_numbers_are_jumpers no)
		(fp_line
			(start 0.7874 -0.4064)
			(end 0.7874 0.4064)
			(stroke
				(width 0.1524)
				(type default)
			)
			(layer "F.SilkS")
		)
		(fp_line
			(start -0.7874 -0.4064)
			(end 0.7874 -0.4064)
			(stroke
				(width 0.1524)
				(type default)
			)
			(layer "F.SilkS")
		)
		(fp_line
			(start 0.7874 0.4064)
			(end -0.7874 0.4064)
			(stroke
				(width 0.1524)
				(type default)
			)
			(layer "F.SilkS")
		)
		(fp_line
			(start -0.7874 0.4064)
			(end -0.7874 -0.4064)
			(stroke
				(width 0.1524)
				(type default)
			)
			(layer "F.SilkS")
		)
		(fp_line
			(start -0.12065 -0.305054)
			(end -0.12065 -0.2794)
			(stroke
				(width 0.1)
				(type default)
			)
			(layer "F.Fab")
		)
		(fp_line
			(start -0.67945 -0.305054)
			(end -0.12065 -0.305054)
			(stroke
				(width 0.1)
				(type default)
			)
			(layer "F.Fab")
		)
		(fp_line
			(start 0.67945 -0.3048)
			(end 0.67945 0.3048)
			(stroke
				(width 0.1)
				(type default)
			)
			(layer "F.Fab")
		)
		(fp_line
			(start 0.12065 -0.3048)
			(end 0.67945 -0.3048)
			(stroke
				(width 0.1)
				(type default)
			)
			(layer "F.Fab")
		)
		(fp_line
			(start 0.12065 -0.2794)
			(end 0.12065 -0.3048)
			(stroke
				(width 0.1)
				(type default)
			)
			(layer "F.Fab")
		)
		(fp_line
			(start -0.12065 -0.2794)
			(end 0.12065 -0.2794)
			(stroke
				(width 0.1)
				(type default)
			)
			(layer "F.Fab")
		)
		(fp_line
			(start 0.120396 0.2794)
			(end -0.12065 0.2794)
			(stroke
				(width 0.1)
				(type default)
			)
			(layer "F.Fab")
		)
		(fp_line
			(start -0.12065 0.2794)
			(end -0.12065 0.3048)
			(stroke
				(width 0.1)
				(type default)
			)
			(layer "F.Fab")
		)
		(fp_line
			(start 0.67945 0.3048)
			(end 0.120396 0.3048)
			(stroke
				(width 0.1)
				(type default)
			)
			(layer "F.Fab")
		)
		(fp_line
			(start 0.120396 0.3048)
			(end 0.120396 0.2794)
			(stroke
				(width 0.1)
				(type default)
			)
			(layer "F.Fab")
		)
		(fp_line
			(start -0.12065 0.3048)
			(end -0.67945 0.3048)
			(stroke
				(width 0.1)
				(type default)
			)
			(layer "F.Fab")
		)
		(fp_line
			(start -0.67945 0.3048)
			(end -0.67945 -0.305054)
			(stroke
				(width 0.1)
				(type default)
			)
			(layer "F.Fab")
		)
		(pad "1" smd circle
			(at -0.40005 0 90)
			(size 0 0)
			(layers "F.Cu" "F.Mask" "F.Paste")
			(net "P12V_AUX")
		)
		(pad "2" smd circle
			(at 0.40005 0 90)
			(size 0 0)
			(layers "F.Cu" "F.Mask" "F.Paste")
			(net "P12V_SCM_OV_FB")
		)
	)
	(footprint ""
		(layer "F.Cu")
		(at 37.681662 -419.249098 -90)
		(property "Reference" "R3293"
			(at 0 0 270)
			(layer "F.SilkS")
			(hide yes)
			(effects
				(font
					(size 1.27 1.27)
				)
			)
		)
		(property "Value" ""
			(at 0 0 270)
			(layer "F.Fab")
			(effects
				(font
					(size 1.27 1.27)
				)
			)
		)
		(duplicate_pad_numbers_are_jumpers no)
		(fp_line
			(start -0.7874 0.4064)
			(end -0.7874 -0.4064)
			(stroke
				(width 0.1524)
				(type default)
			)
			(layer "F.SilkS")
		)
		(fp_line
			(start 0.7874 0.4064)
			(end -0.7874 0.4064)
			(stroke
				(width 0.1524)
				(type default)
			)
			(layer "F.SilkS")
		)
		(fp_line
			(start -0.7874 -0.4064)
			(end 0.7874 -0.4064)
			(stroke
				(width 0.1524)
				(type default)
			)
			(layer "F.SilkS")
		)
		(fp_line
			(start 0.7874 -0.4064)
			(end 0.7874 0.4064)
			(stroke
				(width 0.1524)
				(type default)
			)
			(layer "F.SilkS")
		)
		(fp_line
			(start -0.67945 0.3048)
			(end -0.67945 -0.305054)
			(stroke
				(width 0.1)
				(type default)
			)
			(layer "F.Fab")
		)
		(fp_line
			(start -0.12065 0.3048)
			(end -0.67945 0.3048)
			(stroke
				(width 0.1)
				(type default)
			)
			(layer "F.Fab")
		)
		(fp_line
			(start 0.120396 0.3048)
			(end 0.120396 0.2794)
			(stroke
				(width 0.1)
				(type default)
			)
			(layer "F.Fab")
		)
		(fp_line
			(start 0.67945 0.3048)
			(end 0.120396 0.3048)
			(stroke
				(width 0.1)
				(type default)
			)
			(layer "F.Fab")
		)
		(fp_line
			(start -0.12065 0.2794)
			(end -0.12065 0.3048)
			(stroke
				(width 0.1)
				(type default)
			)
			(layer "F.Fab")
		)
		(fp_line
			(start 0.120396 0.2794)
			(end -0.12065 0.2794)
			(stroke
				(width 0.1)
				(type default)
			)
			(layer "F.Fab")
		)
		(fp_line
			(start -0.12065 -0.2794)
			(end 0.12065 -0.2794)
			(stroke
				(width 0.1)
				(type default)
			)
			(layer "F.Fab")
		)
		(fp_line
			(start 0.12065 -0.2794)
			(end 0.12065 -0.3048)
			(stroke
				(width 0.1)
				(type default)
			)
			(layer "F.Fab")
		)
		(fp_line
			(start 0.12065 -0.3048)
			(end 0.67945 -0.3048)
			(stroke
				(width 0.1)
				(type default)
			)
			(layer "F.Fab")
		)
		(fp_line
			(start 0.67945 -0.3048)
			(end 0.67945 0.3048)
			(stroke
				(width 0.1)
				(type default)
			)
			(layer "F.Fab")
		)
		(fp_line
			(start -0.67945 -0.305054)
			(end -0.12065 -0.305054)
			(stroke
				(width 0.1)
				(type default)
			)
			(layer "F.Fab")
		)
		(fp_line
			(start -0.12065 -0.305054)
			(end -0.12065 -0.2794)
			(stroke
				(width 0.1)
				(type default)
			)
			(layer "F.Fab")
		)
		(pad "1" smd circle
			(at -0.40005 0 270)
			(size 0 0)
			(layers "F.Cu" "F.Mask" "F.Paste")
			(net "FM_P2E_MODE")
		)
		(pad "2" smd circle
			(at 0.40005 0 270)
			(size 0 0)
			(layers "F.Cu" "F.Mask" "F.Paste")
			(net "GND")
		)
	)
	(footprint ""
		(layer "F.Cu")
		(at 33.865058 -170.50766)
		(property "Reference" "R1334"
			(at 0 0 0)
			(layer "F.SilkS")
			(hide yes)
			(effects
				(font
					(size 1.27 1.27)
				)
			)
		)
		(property "Value" ""
			(at 0 0 0)
			(layer "F.Fab")
			(effects
				(font
					(size 1.27 1.27)
				)
			)
		)
		(duplicate_pad_numbers_are_jumpers no)
		(fp_line
			(start -0.7874 -0.4064)
			(end 0.7874 -0.4064)
			(stroke
				(width 0.1524)
				(type default)
			)
			(layer "F.SilkS")
		)
		(fp_line
			(start -0.7874 0.4064)
			(end -0.7874 -0.4064)
			(stroke
				(width 0.1524)
				(type default)
			)
			(layer "F.SilkS")
		)
		(fp_line
			(start 0.7874 -0.4064)
			(end 0.7874 0.4064)
			(stroke
				(width 0.1524)
				(type default)
			)
			(layer "F.SilkS")
		)
		(fp_line
			(start 0.7874 0.4064)
			(end -0.7874 0.4064)
			(stroke
				(width 0.1524)
				(type default)
			)
			(layer "F.SilkS")
		)
		(fp_line
			(start -0.67945 -0.305054)
			(end -0.12065 -0.305054)
			(stroke
				(width 0.1)
				(type default)
			)
			(layer "F.Fab")
		)
		(fp_line
			(start -0.67945 0.3048)
			(end -0.67945 -0.305054)
			(stroke
				(width 0.1)
				(type default)
			)
			(layer "F.Fab")
		)
		(fp_line
			(start -0.12065 -0.305054)
			(end -0.12065 -0.2794)
			(stroke
				(width 0.1)
				(type default)
			)
			(layer "F.Fab")
		)
		(fp_line
			(start -0.12065 -0.2794)
			(end 0.12065 -0.2794)
			(stroke
				(width 0.1)
				(type default)
			)
			(layer "F.Fab")
		)
		(fp_line
			(start -0.12065 0.2794)
			(end -0.12065 0.3048)
			(stroke
				(width 0.1)
				(type default)
			)
			(layer "F.Fab")
		)
		(fp_line
			(start -0.12065 0.3048)
			(end -0.67945 0.3048)
			(stroke
				(width 0.1)
				(type default)
			)
			(layer "F.Fab")
		)
		(fp_line
			(start 0.120396 0.2794)
			(end -0.12065 0.2794)
			(stroke
				(width 0.1)
				(type default)
			)
			(layer "F.Fab")
		)
		(fp_line
			(start 0.120396 0.3048)
			(end 0.120396 0.2794)
			(stroke
				(width 0.1)
				(type default)
			)
			(layer "F.Fab")
		)
		(fp_line
			(start 0.12065 -0.3048)
			(end 0.67945 -0.3048)
			(stroke
				(width 0.1)
				(type default)
			)
			(layer "F.Fab")
		)
		(fp_line
			(start 0.12065 -0.2794)
			(end 0.12065 -0.3048)
			(stroke
				(width 0.1)
				(type default)
			)
			(layer "F.Fab")
		)
		(fp_line
			(start 0.67945 -0.3048)
			(end 0.67945 0.3048)
			(stroke
				(width 0.1)
				(type default)
			)
			(layer "F.Fab")
		)
		(fp_line
			(start 0.67945 0.3048)
			(end 0.120396 0.3048)
			(stroke
				(width 0.1)
				(type default)
			)
			(layer "F.Fab")
		)
		(pad "1" smd rect
			(at -0.40005 0 180)
			(size 0.4572 0.508)
			(layers "F.Cu" "F.Mask" "F.Paste")
			(net "I3C_SPD_DDRAF_CPU1_BYPASS_SCL")
		)
		(pad "2" smd rect
			(at 0.40005 0 180)
			(size 0.4572 0.508)
			(layers "F.Cu" "F.Mask" "F.Paste")
			(net "I3C_SPD_DDRAF_CPU1_SCL")
		)
	)
	(footprint ""
		(layer "F.Cu")
		(at 315.399928 -23.92934)
		(property "Reference" "U99"
			(at -2.032 -2.377948 0)
			(unlocked yes)
			(layer "F.SilkS")
			(effects
				(font
					(size 0.7874 0.5842)
					(thickness 0.1524)
				)
				(justify left)
			)
		)
		(property "Value" ""
			(at 0 0 0)
			(layer "F.Fab")
			(effects
				(font
					(size 1.27 1.27)
				)
			)
		)
		(duplicate_pad_numbers_are_jumpers no)
		(fp_line
			(start -2.0574 -1.651)
			(end -0.381 -1.651)
			(stroke
				(width 0.1524)
				(type default)
			)
			(layer "F.SilkS")
		)
		(fp_line
			(start -2.0574 1.651)
			(end -2.0574 -1.651)
			(stroke
				(width 0.1524)
				(type default)
			)
			(layer "F.SilkS")
		)
		(fp_line
			(start -0.381 -1.651)
			(end 0 -1.016)
			(stroke
				(width 0.1524)
				(type default)
			)
			(layer "F.SilkS")
		)
		(fp_line
			(start 0 -1.016)
			(end 0.381 -1.651)
			(stroke
				(width 0.1524)
				(type default)
			)
			(layer "F.SilkS")
		)
		(fp_line
			(start 0.381 -1.651)
			(end 2.0574 -1.651)
			(stroke
				(width 0.1524)
				(type default)
			)
			(layer "F.SilkS")
		)
		(fp_line
			(start 2.0574 -1.651)
			(end 2.0574 1.651)
			(stroke
				(width 0.1524)
				(type default)
			)
			(layer "F.SilkS")
		)
		(fp_line
			(start 2.0574 1.651)
			(end -2.0574 1.651)
			(stroke
				(width 0.1524)
				(type default)
			)
			(layer "F.SilkS")
		)
		(fp_poly
			(pts
				(xy -2.159 -1.016) (xy -2.71272 -0.719328) (xy -2.71272 -1.344168)
			)
			(stroke
				(width 0)
				(type default)
			)
			(fill yes)
			(layer "F.SilkS")
		)
		(fp_line
			(start -1.599946 -1.199896)
			(end -0.899922 -1.199896)
			(stroke
				(width 0.1)
				(type default)
			)
			(layer "F.Fab")
		)
		(fp_line
			(start -1.599946 1.199896)
			(end -1.599946 -1.199896)
			(stroke
				(width 0.1)
				(type default)
			)
			(layer "F.Fab")
		)
		(fp_line
			(start -0.899922 -1.549908)
			(end 0.899922 -1.549908)
			(stroke
				(width 0.1)
				(type default)
			)
			(layer "F.Fab")
		)
		(fp_line
			(start -0.899922 -1.199896)
			(end -0.899922 -1.549908)
			(stroke
				(width 0.1)
				(type default)
			)
			(layer "F.Fab")
		)
		(fp_line
			(start -0.899922 1.199896)
			(end -1.599946 1.199896)
			(stroke
				(width 0.1)
				(type default)
			)
			(layer "F.Fab")
		)
		(fp_line
			(start -0.899922 1.549908)
			(end -0.899922 1.199896)
			(stroke
				(width 0.1)
				(type default)
			)
			(layer "F.Fab")
		)
		(fp_line
			(start 0.899922 -1.549908)
			(end 0.899922 -1.199896)
			(stroke
				(width 0.1)
				(type default)
			)
			(layer "F.Fab")
		)
		(fp_line
			(start 0.899922 -1.199896)
			(end 1.599946 -1.199896)
			(stroke
				(width 0.1)
				(type default)
			)
			(layer "F.Fab")
		)
		(fp_line
			(start 0.899922 1.199896)
			(end 0.899922 1.549908)
			(stroke
				(width 0.1)
				(type default)
			)
			(layer "F.Fab")
		)
		(fp_line
			(start 0.899922 1.549908)
			(end -0.899922 1.549908)
			(stroke
				(width 0.1)
				(type default)
			)
			(layer "F.Fab")
		)
		(fp_line
			(start 1.599946 -1.199896)
			(end 1.599946 1.199896)
			(stroke
				(width 0.1)
				(type default)
			)
			(layer "F.Fab")
		)
		(fp_line
			(start 1.599946 1.199896)
			(end 0.899922 1.199896)
			(stroke
				(width 0.1)
				(type default)
			)
			(layer "F.Fab")
		)
		(fp_poly
			(pts
				(xy -2.71272 -0.719328) (xy -2.71272 -1.344168) (xy -2.159 -1.016)
			)
			(stroke
				(width 0)
				(type default)
			)
			(fill yes)
			(layer "F.Fab")
		)
		(pad "1" smd rect
			(at -1.225042 -0.94996 270)
			(size 0.5588 1.3462)
			(layers "F.Cu" "F.Mask" "F.Paste")
			(net "Net_10727")
		)
		(pad "2" smd rect
			(at -1.225042 0 270)
			(size 0.5588 1.3462)
			(layers "F.Cu" "F.Mask" "F.Paste")
			(net "FW_RECOVERY_R")
		)
		(pad "3" smd rect
			(at -1.225042 0.94996 270)
			(size 0.5588 1.3462)
			(layers "F.Cu" "F.Mask" "F.Paste")
			(net "GND")
		)
		(pad "4" smd rect
			(at 1.225042 0.94996 270)
			(size 0.5588 1.3462)
			(layers "F.Cu" "F.Mask" "F.Paste")
			(net "SCM_JTAG_MUX_S1")
		)
		(pad "5" smd rect
			(at 1.225042 -0.94996 270)
			(size 0.5588 1.3462)
			(layers "F.Cu" "F.Mask" "F.Paste")
			(net "P3V3_AUX")
		)
	)
	(footprint ""
		(layer "F.Cu")
		(at 414.325562 -361.814364 180)
		(property "Reference" "PR129"
			(at 0 0 180)
			(layer "F.SilkS")
			(hide yes)
			(effects
				(font
					(size 1.27 1.27)
				)
			)
		)
		(property "Value" ""
			(at 0 0 180)
			(layer "F.Fab")
			(effects
				(font
					(size 1.27 1.27)
				)
			)
		)
		(duplicate_pad_numbers_are_jumpers no)
		(fp_line
			(start 0.7874 0.4064)
			(end -0.7874 0.4064)
			(stroke
				(width 0.1524)
				(type default)
			)
			(layer "F.SilkS")
		)
		(fp_line
			(start 0.7874 -0.4064)
			(end 0.7874 0.4064)
			(stroke
				(width 0.1524)
				(type default)
			)
			(layer "F.SilkS")
		)
		(fp_line
			(start -0.7874 0.4064)
			(end -0.7874 -0.4064)
			(stroke
				(width 0.1524)
				(type default)
			)
			(layer "F.SilkS")
		)
		(fp_line
			(start -0.7874 -0.4064)
			(end 0.7874 -0.4064)
			(stroke
				(width 0.1524)
				(type default)
			)
			(layer "F.SilkS")
		)
		(fp_line
			(start 0.67945 0.3048)
			(end 0.120396 0.3048)
			(stroke
				(width 0.1)
				(type default)
			)
			(layer "F.Fab")
		)
		(fp_line
			(start 0.67945 -0.3048)
			(end 0.67945 0.3048)
			(stroke
				(width 0.1)
				(type default)
			)
			(layer "F.Fab")
		)
		(fp_line
			(start 0.12065 -0.2794)
			(end 0.12065 -0.3048)
			(stroke
				(width 0.1)
				(type default)
			)
			(layer "F.Fab")
		)
		(fp_line
			(start 0.12065 -0.3048)
			(end 0.67945 -0.3048)
			(stroke
				(width 0.1)
				(type default)
			)
			(layer "F.Fab")
		)
		(fp_line
			(start 0.120396 0.3048)
			(end 0.120396 0.2794)
			(stroke
				(width 0.1)
				(type default)
			)
			(layer "F.Fab")
		)
		(fp_line
			(start 0.120396 0.2794)
			(end -0.12065 0.2794)
			(stroke
				(width 0.1)
				(type default)
			)
			(layer "F.Fab")
		)
		(fp_line
			(start -0.12065 0.3048)
			(end -0.67945 0.3048)
			(stroke
				(width 0.1)
				(type default)
			)
			(layer "F.Fab")
		)
		(fp_line
			(start -0.12065 0.2794)
			(end -0.12065 0.3048)
			(stroke
				(width 0.1)
				(type default)
			)
			(layer "F.Fab")
		)
		(fp_line
			(start -0.12065 -0.2794)
			(end 0.12065 -0.2794)
			(stroke
				(width 0.1)
				(type default)
			)
			(layer "F.Fab")
		)
		(fp_line
			(start -0.12065 -0.305054)
			(end -0.12065 -0.2794)
			(stroke
				(width 0.1)
				(type default)
			)
			(layer "F.Fab")
		)
		(fp_line
			(start -0.67945 0.3048)
			(end -0.67945 -0.305054)
			(stroke
				(width 0.1)
				(type default)
			)
			(layer "F.Fab")
		)
		(fp_line
			(start -0.67945 -0.305054)
			(end -0.12065 -0.305054)
			(stroke
				(width 0.1)
				(type default)
			)
			(layer "F.Fab")
		)
		(pad "1" smd circle
			(at -0.40005 0 180)
			(size 0 0)
			(layers "F.Cu" "F.Mask" "F.Paste")
			(net "PVDD11_S3_P0_RESET_N_R")
		)
		(pad "2" smd circle
			(at 0.40005 0 180)
			(size 0 0)
			(layers "F.Cu" "F.Mask" "F.Paste")
			(net "PVDD11_S3_P0_RESET_N")
		)
	)
)
